FILE_TYPE = CONNECTIVITY;
{Allegro Design Entry HDL 17.4-2019 S026 (4007227) 1/17/2022}
"PAGE_NUMBER" = 476;
0"NC";
1"P5V_AUX\g";
2"P3V3_AUX\g";
3"GND\g";
4"GND\g";
5"GND\g";
6"GND\g";
7"GND\g";
8"GND\g";
9"GND\g";
10"GND\g";
11"GND\g";
12"GND\g";
13"GND\g";
14"GND\g";
15"GND\g";
16"GND\g";
17"GND\g";
18"GND\g";
19"GND\g";
20"GND\g";
21"GND\g";
22"GND\g";
23"GND\g";
24"GND\g";
25"GND\g";
26"GND\g";
27"GND\g";
28"GND\g";
29"GND\g";
30"GND\g";
31"GND\g";
32"P12V_AUX\g";
33"P0V9_RETIMER_CPU0_IMON1";
34"PV09_RETIMER_CPU0_VCCS";
35"P0V9_CPU0_RT_2D\g";
36"GND\g";
37"GND\g";
38"SW_P12V_AUX_P0V9_RETIMER_CPU0_FLT\g";
39"SW_P12V_AUX_P0V9_RETIMER_CPU0_FLT\g";
40"P0V9_CPU0_RT_2D\g";
41"GND\g";
42"GND\g";
43"P0V9_RETIMER_CPU0_PVCC\g";
44"P0V9_RETIMER_CPU0_PVCC\g";
45"SW_P0V9_RETIMER_CPU0_SW1";
46"P0V9_RETIMER_CPU0_VCC1";
47"SW_P0V9_RETIMER_CPU0_BOOT1";
48"SW_P0V9_RETIMER_CPU0_PH1";
49"P0V9_RETIMER_CPU0_VOS1";
50"SW_P0V9_RETIMER_CPU0_BOOT1_RC";
51"SW_P0V9_RETIMER_CPU0_BOOT2";
52"SW_P0V9_RETIMER_CPU0_BOOT2_RC";
53"NC_PV09_RETIMER_CPU0_GL1_1";
54"P0V9_RETIMER_CPU0_TEMP0";
55"P0V9_RETIMER_CPU0_PWM1";
56"P0V9_RETIMER_CPU0_TEMP0";
57"NC_PV09_RETIMER_CPU0_DNC2";
58"P0V9_RETIMER_CPU0_IMON2";
59"SW_P0V9_RETIMER_CPU0_SW2";
60"NC_PV09_RETIMER_CPU0_GL2_2";
61"NC_PV09_RETIMER_CPU0_GL1_2";
62"SW_P0V9_RETIMER_CPU0_SW2_RC";
63"SW_P0V9_RETIMER_CPU0_SW1_RC";
64"NC_PV09_RETIMER_CPU0_DNC1";
65"P0V9_RETIMER_CPU0_LSET1";
66"P0V9_RETIMER_CPU0_VOS2";
67"P0V9_RETIMER_CPU0_PWM2";
68"P0V9_RETIMER_CPU0_LSET2";
69"PV09_RETIMER_CPU0_VCCS";
70"SW_P0V9_RETIMER_CPU0_PH2";
71"NC_PV09_RETIMER_CPU0_GL2_1";
72"P0V9_RETIMER_CPU0_VCC2";
%"VCC15"
"1","(1600,-6125)","0","pure_quanta_power","I1";
;
HDL_POWER"P0V9_CPU0_RT_2D"
CDS_LIB"pure_quanta_power"
BOM_COST"VR_DIMM ";
"A"35;
%"Q_INDUCTOR"
"1","(1150,-5450)","0","pure_quanta","I182";
;
LOCATION"PL6504"
SEC"1"
VALUE"100NH/16A"
MATERIAL"IND"
PACK_TYPE"SMLF"
CDS_LIB"pure_quanta"
SEC_TYPE"SMLF"
NEEDS_NO_SIZE"TRUE"
PART_NUMBER"CV+10G0MZ04";
"1"
$PN"1"38;
"2"
$PN"2"32;
%"Q_RES"
"2","(-6450,-4650)","0","pure_quanta","I183";
;
LOCATION"PR6550"
SEC"1"
TOLERANCE"5%"
MATERIAL"CHIP"
PACK_TYPE"0402LF"
VALUE"0"
WATTAGE"1/16W"
CDS_LIB"pure_quanta"
SEC_TYPE"0402LF"
PART_NUMBER"CS00002JB13";
"A"
$PN"1"1;
"B"
$PN"2"44;
%"UNIVERSAL_POWER"
"1","(-6450,-4350)","0","pure_quanta_power","I184";
;
HDL_POWER"P5V_AUX"
CDS_LIB"pure_quanta_power";
"A"1;
%"Q_RES"
"2","(-5550,-4650)","0","pure_quanta","I185";
;
LOCATION"PR6551"
SEC"1"
TOLERANCE"5%"
VALUE"0"
WATTAGE"1/16W"
PACK_TYPE"0402LF"
MATERIAL"EMPTY"
CDS_LIB"pure_quanta"
SEC_TYPE"0402LF"
PART_NUMBER"CS00002JB13";
"A"
$PN"1"2;
"B"
$PN"2"44;
%"UNIVERSAL_POWER"
"1","(-5550,-4350)","0","pure_quanta_power","I186";
;
HDL_POWER"P3V3_AUX"
CDS_LIB"pure_quanta_power";
"A"2;
%"Q_RES"
"2","(975,-6625)","0","pure_quanta","I187";
;
LOCATION"PR6557"
SEC"1"
TOLERANCE"1%"
PACK_TYPE"0603LF"
MATERIAL"CHIP"
VALUE"499"
WATTAGE"1/10W"
CDS_LIB"pure_quanta"
SEC_TYPE"0603LF"
PART_NUMBER"CS14993F901";
"A"
$PN"1"35;
"B"
$PN"2"37;
%"UNIVERSAL_GND"
"1","(-6650,-7075)","0","pure_quanta_power","I188";
;
CDS_LIB"pure_quanta_power"
HDL_POWER"GND";
"A"3;
%"UNIVERSAL_GND"
"1","(-5850,-7250)","0","pure_quanta_power","I189";
;
CDS_LIB"pure_quanta_power"
HDL_POWER"GND";
"A"4;
%"UNIVERSAL_GND"
"1","(-5900,-6225)","0","pure_quanta_power","I190";
;
CDS_LIB"pure_quanta_power"
HDL_POWER"GND";
"A"5;
%"UNIVERSAL_GND"
"1","(-5200,-5750)","0","pure_quanta_power","I191";
;
CDS_LIB"pure_quanta_power"
HDL_POWER"GND";
"A"6;
%"UNIVERSAL_GND"
"1","(-3525,-7250)","0","pure_quanta_power","I192";
;
CDS_LIB"pure_quanta_power"
HDL_POWER"GND";
"A"36;
%"UNIVERSAL_GND"
"1","(600,-5950)","0","pure_quanta_power","I193";
;
CDS_LIB"pure_quanta_power"
HDL_POWER"GND";
"A"7;
%"UNIVERSAL_GND"
"1","(-1025,-5925)","0","pure_quanta_power","I194";
;
CDS_LIB"pure_quanta_power"
HDL_POWER"GND";
"A"8;
%"UNIVERSAL_GND"
"1","(-1500,-5925)","0","pure_quanta_power","I195";
;
CDS_LIB"pure_quanta_power"
HDL_POWER"GND";
"A"9;
%"UNIVERSAL_GND"
"1","(-2000,-5925)","0","pure_quanta_power","I196";
;
CDS_LIB"pure_quanta_power"
HDL_POWER"GND";
"A"10;
%"UNIVERSAL_GND"
"1","(-3000,-5925)","0","pure_quanta_power","I197";
;
CDS_LIB"pure_quanta_power"
HDL_POWER"GND";
"A"11;
%"UNIVERSAL_GND"
"1","(-2500,-5925)","0","pure_quanta_power","I198";
;
CDS_LIB"pure_quanta_power"
HDL_POWER"GND";
"A"12;
%"UNIVERSAL_GND"
"1","(975,-6925)","0","pure_quanta_power","I199";
;
CDS_LIB"pure_quanta_power"
HDL_POWER"GND";
"A"37;
%"Q_CAP"
"1","(-825,-6600)","0","pure_quanta","I202";
;
LOCATION"PC6566_1"
$SEC"1"
CDS_SEC"1"
VALUE"22UF"
MATERIAL"X6S"
PACK_TYPE"C0805"
TOLERANCE"20%"
VOLTAGE"4V"
CDS_LIB"pure_quanta"
PART_NUMBER"CH622KMEA03";
"B"
$PN"2"37;
"A"
$PN"1"35;
%"Q_CAPP"
"1","(600,-5675)","0","pure_quanta","I209";
;
LOCATION"PC6561"
$SEC"1"
CDS_SEC"1"
MATERIAL"OSCON"
VOLTAGE"16V"
PACK_TYPE"SMLF"
TOLERANCE"20%"
VALUE"100UF"
CDS_LIB"pure_quanta"
PART_NUMBER"CC71003MZ30";
"A"
$PN"1"38;
"B"
$PN"2"7;
%"Q_CAP"
"1","(-1025,-5650)","0","pure_quanta","I21";
;
LOCATION"PC6558_1"
$SEC"1"
CDS_SEC"1"
PACK_TYPE"C0805"
TOLERANCE"20%"
MATERIAL"X6S"
VOLTAGE"16V"
VALUE"22UF"
CDS_LIB"pure_quanta"
REUSE_ID"41"
BOM_COST"VR_DIMM "
PART_NUMBER"CH6223MEA01";
"B"
$PN"2"8;
"A"
$PN"1"38;
%"Q_CAP"
"1","(-650,-5650)","0","pure_quanta","I210";
;
LOCATION"PC6559_1"
SEC"1"
MATERIAL"X6S"
VOLTAGE"16V"
TOLERANCE"20%"
PACK_TYPE"C0805"
VALUE"22UF"
CDS_LIB"pure_quanta"
SEC_TYPE"C0805"
BOM_COST"VR_DIMM "
REUSE_ID"41"
PART_NUMBER"CH6223MEA01";
"B"
$PN"2"13;
"A"
$PN"1"38;
%"UNIVERSAL_GND"
"1","(-650,-5925)","0","pure_quanta_power","I211";
;
CDS_LIB"pure_quanta_power"
HDL_POWER"GND";
"A"13;
%"UNIVERSAL_GND"
"1","(-250,-5925)","0","pure_quanta_power","I214";
;
CDS_LIB"pure_quanta_power"
HDL_POWER"GND";
"A"14;
%"UNIVERSAL_GND"
"1","(200,-5925)","0","pure_quanta_power","I215";
;
CDS_LIB"pure_quanta_power"
HDL_POWER"GND";
"A"15;
%"Q_CAP"
"1","(200,-5700)","0","pure_quanta","I216";
;
LOCATION"PC6816"
SEC"1"
VALUE"22UF"
VOLTAGE"16V"
TOLERANCE"20%"
MATERIAL"X6S"
PACK_TYPE"C0805"
CDS_LIB"pure_quanta"
SEC_TYPE"C0805"
PART_NUMBER"CH6223MEA01";
"B"
$PN"2"15;
"A"
$PN"1"38;
%"Q_CAP"
"1","(-250,-5700)","0","pure_quanta","I217";
;
LOCATION"PC6560"
SEC"1"
TOLERANCE"20%"
MATERIAL"X6S"
VOLTAGE"16V"
PACK_TYPE"C0805"
VALUE"22UF"
CDS_LIB"pure_quanta"
SEC_TYPE"C0805"
PART_NUMBER"CH6223MEA01";
"B"
$PN"2"14;
"A"
$PN"1"38;
%"Q_RES"
"2","(-5850,-7000)","0","pure_quanta","I220";
;
LOCATION"PR6553"
SEC"1"
MATERIAL"EMPTY"
VALUE"8.87K"
TOLERANCE"1%"
PACK_TYPE"0402LF"
WATTAGE"1/16W"
CDS_LIB"pure_quanta"
SEC_TYPE"0402LF"
PART_NUMBER"CS28872FB01";
"A"
$PN"1"65;
"B"
$PN"2"4;
%"Q_RES"
"1","(-2500,-6100)","0","pure_quanta","I221";
;
LOCATION"PR6554"
SEC"1"
MATERIAL"CHIP"
WATTAGE"1/16W"
VALUE"5.6"
TOLERANCE"1%"
PACK_TYPE"0402LF"
CDS_LIB"pure_quanta"
SEC_TYPE"0402LF"
PART_NUMBER"CS-5602FB01";
"B"
$PN"2"50;
"A"
$PN"1"47;
%"Q_CAPP"
"1","(625,-6600)","0","pure_quanta","I222";
;
LOCATION"PC6572"
$SEC"1"
CDS_SEC"1"
MATERIAL"ALUM"
VALUE"390UF"
PACK_TYPE"SMLF"
VOLTAGE"2.5V"
TOLERANCE"20%"
CDS_LIB"pure_quanta"
PART_NUMBER"CC7390JMZ13";
"A"
$PN"1"35;
"B"
$PN"2"37;
%"Q_CAP"
"1","(-600,-6600)","0","pure_quanta","I223";
;
LOCATION"PC6567_1"
$SEC"1"
CDS_SEC"1"
PACK_TYPE"C0805"
MATERIAL"X6S"
TOLERANCE"20%"
VALUE"22UF"
VOLTAGE"4V"
CDS_LIB"pure_quanta"
PART_NUMBER"CH622KMEA03";
"B"
$PN"2"37;
"A"
$PN"1"35;
%"Q_CAPP"
"1","(-375,-6600)","0","pure_quanta","I224";
;
LOCATION"PC6568"
$SEC"1"
CDS_SEC"1"
PACK_TYPE"SMLF"
VALUE"470UF"
TOLERANCE"20%"
VOLTAGE"2.5V"
MATERIAL"SPCAP"
CDS_LIB"pure_quanta"
PART_NUMBER"CH747LM8818";
"A"
$PN"1"35;
"B"
$PN"2"37;
%"Q_CAPP"
"1","(-150,-6600)","0","pure_quanta","I225";
;
LOCATION"PC6569"
$SEC"1"
CDS_SEC"1"
TOLERANCE"20%"
VALUE"470UF"
PACK_TYPE"SMLF"
VOLTAGE"2.5V"
MATERIAL"SPCAP"
CDS_LIB"pure_quanta"
PART_NUMBER"CH747LM8818";
"A"
$PN"1"35;
"B"
$PN"2"37;
%"Q_CAPP"
"1","(50,-6600)","0","pure_quanta","I226";
;
LOCATION"PC6570"
$SEC"1"
CDS_SEC"1"
TOLERANCE"20%"
PACK_TYPE"SMLF"
VALUE"470UF"
VOLTAGE"2.5V"
MATERIAL"SPCAP"
CDS_LIB"pure_quanta"
PART_NUMBER"CH747LM8818";
"A"
$PN"1"35;
"B"
$PN"2"37;
%"Q_CAPP"
"1","(375,-6600)","0","pure_quanta","I227";
;
LOCATION"PC6571"
$SEC"1"
CDS_SEC"1"
TOLERANCE"20%"
MATERIAL"ALUM"
PACK_TYPE"SMLF"
VALUE"390UF"
VOLTAGE"2.5V"
CDS_LIB"pure_quanta"
PART_NUMBER"CC7390JMZ13";
"A"
$PN"1"35;
"B"
$PN"2"37;
%"VCC15"
"1","(550,-5250)","0","pure_quanta_power","I23";
;
HDL_POWER"SW_P12V_AUX_P0V9_RETIMER_CPU0_FLT"
CDS_LIB"pure_quanta_power"
BOM_COST"VR_DIMM ";
"A"38;
%"VCC15"
"1","(675,-8150)","0","pure_quanta_power","I230";
;
HDL_POWER"SW_P12V_AUX_P0V9_RETIMER_CPU0_FLT"
CDS_LIB"pure_quanta_power"
BOM_COST"VR_DIMM ";
"A"39;
%"Q_CAPP"
"1","(725,-8575)","0","pure_quanta","I231";
;
LOCATION"PC6810"
$SEC"1"
CDS_SEC"1"
VALUE"100UF"
VOLTAGE"16V"
TOLERANCE"20%"
MATERIAL"OSCON"
PACK_TYPE"SMLF"
CDS_LIB"pure_quanta"
PART_NUMBER"CC71003MZ30";
"A"
$PN"1"39;
"B"
$PN"2"16;
%"Q_CAP"
"1","(325,-8600)","0","pure_quanta","I232";
;
LOCATION"PC6817"
$SEC"1"
CDS_SEC"1"
VOLTAGE"16V"
TOLERANCE"20%"
VALUE"22UF"
PACK_TYPE"C0805"
MATERIAL"X6S"
CDS_LIB"pure_quanta"
PART_NUMBER"CH6223MEA01";
"B"
$PN"2"17;
"A"
$PN"1"39;
%"VCC15"
"1","(1725,-9025)","0","pure_quanta_power","I233";
;
HDL_POWER"P0V9_CPU0_RT_2D"
CDS_LIB"pure_quanta_power"
BOM_COST"VR_DIMM ";
"A"40;
%"UNIVERSAL_GND"
"1","(725,-8850)","0","pure_quanta_power","I234";
;
CDS_LIB"pure_quanta_power"
HDL_POWER"GND";
"A"16;
%"Q_CAPP"
"1","(750,-9500)","0","pure_quanta","I236";
;
LOCATION"PC6574"
$SEC"1"
CDS_SEC"1"
MATERIAL"ALUM"
PACK_TYPE"SMLF"
TOLERANCE"20%"
VOLTAGE"2.5V"
VALUE"390UF"
CDS_LIB"pure_quanta"
PART_NUMBER"CC7390JMZ13";
"A"
$PN"1"40;
"B"
$PN"2"41;
%"UNIVERSAL_GND"
"1","(325,-8825)","0","pure_quanta_power","I237";
;
CDS_LIB"pure_quanta_power"
HDL_POWER"GND";
"A"17;
%"Q_CAPP"
"1","(500,-9500)","0","pure_quanta","I238";
;
LOCATION"PC6573"
$SEC"1"
CDS_SEC"1"
VOLTAGE"2.5V"
MATERIAL"ALUM"
PACK_TYPE"SMLF"
TOLERANCE"20%"
VALUE"390UF"
CDS_LIB"pure_quanta"
PART_NUMBER"CC7390JMZ13";
"A"
$PN"1"40;
"B"
$PN"2"41;
%"Q_CAPP"
"1","(175,-9500)","0","pure_quanta","I239";
;
LOCATION"PC534"
$SEC"1"
CDS_SEC"1"
VALUE"470UF"
MATERIAL"SPCAP"
TOLERANCE"20%"
VOLTAGE"2.5V"
PACK_TYPE"SMLF"
CDS_LIB"pure_quanta"
PART_NUMBER"CH747LM8818";
"A"
$PN"1"40;
"B"
$PN"2"41;
%"Q_CAP"
"1","(-1500,-5650)","0","pure_quanta","I24";
;
LOCATION"PC6557_1"
$SEC"1"
CDS_SEC"1"
TOLERANCE"20%"
MATERIAL"X6S"
VOLTAGE"16V"
PACK_TYPE"C0805"
VALUE"22UF"
CDS_LIB"pure_quanta"
BOM_COST"VR_DIMM "
REUSE_ID"41"
PART_NUMBER"CH6223MEA01";
"B"
$PN"2"9;
"A"
$PN"1"38;
%"UNIVERSAL_GND"
"1","(750,-9850)","0","pure_quanta_power","I240";
;
CDS_LIB"pure_quanta_power"
HDL_POWER"GND";
"A"41;
%"Q_CAP"
"1","(-125,-8600)","0","pure_quanta","I241";
;
LOCATION"PC6583"
$SEC"1"
CDS_SEC"1"
MATERIAL"X6S"
TOLERANCE"20%"
VALUE"22UF"
PACK_TYPE"C0805"
VOLTAGE"16V"
CDS_LIB"pure_quanta"
PART_NUMBER"CH6223MEA01";
"B"
$PN"2"18;
"A"
$PN"1"39;
%"Q_CAP"
"1","(-525,-8550)","0","pure_quanta","I242";
;
LOCATION"PC6582_2"
$SEC"1"
CDS_SEC"1"
PACK_TYPE"C0805"
TOLERANCE"20%"
VOLTAGE"16V"
VALUE"22UF"
MATERIAL"X6S"
REUSE_ID"41"
BOM_COST"VR_DIMM "
CDS_LIB"pure_quanta"
PART_NUMBER"CH6223MEA01";
"B"
$PN"2"19;
"A"
$PN"1"39;
%"Q_CAP"
"1","(-900,-8550)","0","pure_quanta","I243";
;
LOCATION"PC6581_2"
$SEC"1"
CDS_SEC"1"
VALUE"22UF"
VOLTAGE"16V"
TOLERANCE"20%"
PACK_TYPE"C0805"
MATERIAL"X6S"
CDS_LIB"pure_quanta"
REUSE_ID"41"
BOM_COST"VR_DIMM "
PART_NUMBER"CH6223MEA01";
"B"
$PN"2"20;
"A"
$PN"1"39;
%"Q_CAP"
"1","(-1375,-8550)","0","pure_quanta","I244";
;
LOCATION"PC6580_2"
$SEC"1"
CDS_SEC"1"
TOLERANCE"20%"
VOLTAGE"16V"
VALUE"22UF"
MATERIAL"X6S"
PACK_TYPE"C0805"
REUSE_ID"41"
BOM_COST"VR_DIMM "
CDS_LIB"pure_quanta"
PART_NUMBER"CH6223MEA01";
"B"
$PN"2"21;
"A"
$PN"1"39;
%"Q_CAP"
"1","(-1875,-8550)","0","pure_quanta","I245";
;
LOCATION"PC6579_2"
$SEC"1"
CDS_SEC"1"
TOLERANCE"20%"
MATERIAL"X6S"
VOLTAGE"16V"
VALUE"22UF"
PACK_TYPE"C0805"
CDS_LIB"pure_quanta"
BOM_COST"VR_DIMM "
REUSE_ID"41"
PART_NUMBER"CH6223MEA01";
"B"
$PN"2"22;
"A"
$PN"1"39;
%"UNIVERSAL_GND"
"1","(-125,-8825)","0","pure_quanta_power","I246";
;
CDS_LIB"pure_quanta_power"
HDL_POWER"GND";
"A"18;
%"Q_CAPP"
"1","(-25,-9500)","0","pure_quanta","I247";
;
LOCATION"PC6811"
$SEC"1"
CDS_SEC"1"
TOLERANCE"20%"
VALUE"470UF"
VOLTAGE"2.5V"
MATERIAL"SPCAP"
PACK_TYPE"SMLF"
CDS_LIB"pure_quanta"
PART_NUMBER"CH747LM8818";
"A"
$PN"1"40;
"B"
$PN"2"41;
%"Q_CAPP"
"1","(-250,-9500)","0","pure_quanta","I248";
;
LOCATION"PC6812"
$SEC"1"
CDS_SEC"1"
TOLERANCE"20%"
VALUE"470UF"
VOLTAGE"2.5V"
MATERIAL"SPCAP"
PACK_TYPE"SMLF"
CDS_LIB"pure_quanta"
PART_NUMBER"CH747LM8818";
"A"
$PN"1"40;
"B"
$PN"2"41;
%"UNIVERSAL_GND"
"1","(-525,-8825)","0","pure_quanta_power","I249";
;
CDS_LIB"pure_quanta_power"
HDL_POWER"GND";
"A"19;
%"Q_CAP"
"1","(-475,-9500)","0","pure_quanta","I250";
;
LOCATION"PC6587_2"
$SEC"1"
CDS_SEC"1"
TOLERANCE"20%"
VOLTAGE"4V"
VALUE"22UF"
MATERIAL"X6S"
PACK_TYPE"C0805"
CDS_LIB"pure_quanta"
PART_NUMBER"CH622KMEA03";
"B"
$PN"2"41;
"A"
$PN"1"40;
%"Q_CAP"
"1","(-700,-9500)","0","pure_quanta","I251";
;
LOCATION"PC6586_2"
$SEC"1"
CDS_SEC"1"
MATERIAL"X6S"
PACK_TYPE"C0805"
VOLTAGE"4V"
VALUE"22UF"
TOLERANCE"20%"
CDS_LIB"pure_quanta"
PART_NUMBER"CH622KMEA03";
"B"
$PN"2"41;
"A"
$PN"1"40;
%"UNIVERSAL_GND"
"1","(-900,-8825)","0","pure_quanta_power","I252";
;
CDS_LIB"pure_quanta_power"
HDL_POWER"GND";
"A"20;
%"Q_CAP"
"2","(-1000,-9000)","0","pure_quanta","I253";
;
LOCATION"PC6584"
$SEC"1"
CDS_SEC"1"
VALUE"100NF"
MATERIAL"X7R"
TOLERANCE"10%"
VOLTAGE"50V"
PACK_TYPE"C0402"
CDS_LIB"pure_quanta"
REUSE_ID"55"
BOM_COST"VR_DIMM "
PART_NUMBER"CH4106K1B01";
"A"
$PN"1"52;
"B"
$PN"2"70;
%"UNIVERSAL_GND"
"1","(-1375,-8825)","0","pure_quanta_power","I254";
;
CDS_LIB"pure_quanta_power"
HDL_POWER"GND";
"A"21;
%"Q_CAP"
"1","(-1025,-9500)","0","pure_quanta","I255";
;
LOCATION"PC6806"
$SEC"1"
CDS_SEC"1"
TOLERANCE"10%"
PACK_TYPE"C0402"
MATERIAL"X7R"
VOLTAGE"50V"
VALUE"100NF"
BOM_COST"VR_DIMM "
CDS_LIB"pure_quanta"
PART_NUMBER"CH4106K1B01";
"B"
$PN"2"41;
"A"
$PN"1"40;
%"UNIVERSAL_GND"
"1","(-1875,-8825)","0","pure_quanta_power","I256";
;
CDS_LIB"pure_quanta_power"
HDL_POWER"GND";
"A"22;
%"Q_INDUCTOR"
"1","(-1825,-9325)","0","pure_quanta","I257";
;
LOCATION"PL6506"
$SEC"1"
CDS_SEC"1"
PACK_TYPE"SMLF"
VALUE"120NH/69A"
MATERIAL"IND"
NEEDS_NO_SIZE"TRUE"
BOM_COST"VR_DIMM "
CDS_LIB"pure_quanta"
PART_NUMBER"CV+12^0EZ03";
"1"
$PN"1"59;
"2"
$PN"2"40;
%"Q_CAP"
"1","(-2375,-8550)","0","pure_quanta","I258";
;
LOCATION"PC6577_2"
$SEC"1"
CDS_SEC"1"
VALUE"1UF"
TOLERANCE"10%"
MATERIAL"X6S"
VOLTAGE"25V"
PACK_TYPE"C0402"
CDS_LIB"pure_quanta"
BOM_COST"VR_DIMM "
PART_NUMBER"CH5104KEB02";
"B"
$PN"2"23;
"A"
$PN"1"39;
%"Q_CAP"
"1","(-2875,-8550)","0","pure_quanta","I259";
;
LOCATION"PC6578_2"
$SEC"1"
CDS_SEC"1"
TOLERANCE"10%"
VALUE"3300PF"
VOLTAGE"50V"
MATERIAL"X7R"
PACK_TYPE"0402"
CDS_LIB"pure_quanta"
BOM_COST"VR_DIMM "
PART_NUMBER"TMP_QCH2336K1B12";
"B"
$PN"2"24;
"A"
$PN"1"39;
%"UNIVERSAL_GND"
"1","(-2375,-8825)","0","pure_quanta_power","I260";
;
CDS_LIB"pure_quanta_power"
HDL_POWER"GND";
"A"23;
%"UNIVERSAL_GND"
"1","(-2875,-8825)","0","pure_quanta_power","I261";
;
CDS_LIB"pure_quanta_power"
HDL_POWER"GND";
"A"24;
%"Q_RES"
"1","(-2375,-9000)","0","pure_quanta","I262";
;
LOCATION"PR6562"
$SEC"1"
CDS_SEC"1"
MATERIAL"CHIP"
PACK_TYPE"0402LF"
TOLERANCE"1%"
WATTAGE"1/16W"
VALUE"5.6"
CDS_LIB"pure_quanta"
PART_NUMBER"CS-5602FB01";
"B"
$PN"2"52;
"A"
$PN"1"51;
%"Q_RES"
"1","(-1950,-10425)","0","pure_quanta","I263";
;
LOCATION"PR6564"
$SEC"1"
CDS_SEC"1"
MATERIAL"CHIP"
WATTAGE"1/16W"
PACK_TYPE"0402LF"
VALUE"0"
TOLERANCE"5%"
BOM_COST"VR_DIMM "
CDS_LIB"pure_quanta"
PART_NUMBER"CS00002JB13";
"B"
$PN"2"40;
"A"
$PN"1"66;
%"UNIVERSAL_GND"
"1","(-3400,-10150)","0","pure_quanta_power","I264";
;
CDS_LIB"pure_quanta_power"
HDL_POWER"GND";
"A"42;
%"UNIVERSAL_POWER"
"1","(-5775,-7750)","0","pure_quanta_power","I265";
;
HDL_POWER"P0V9_RETIMER_CPU0_PVCC"
CDS_LIB"pure_quanta_power";
"A"43;
%"Q_CAP"
"1","(-5075,-8400)","0","pure_quanta","I267";
;
LOCATION"PC6551_09P0_2"
$SEC"1"
CDS_SEC"1"
VALUE"2.2UF"
VOLTAGE"10V"
TOLERANCE"10%"
MATERIAL"X6S"
PACK_TYPE"C0402"
CDS_LIB"pure_quanta"
BOM_COST"VR_DIMM "
PART_NUMBER"CH5222KEB01";
"B"
$PN"2"25;
"A"
$PN"1"43;
%"UNIVERSAL_GND"
"1","(-5075,-8650)","0","pure_quanta_power","I268";
;
CDS_LIB"pure_quanta_power"
HDL_POWER"GND";
"A"25;
%"Q_RES"
"2","(-5775,-8400)","0","pure_quanta","I269";
;
LOCATION"PR6560"
$SEC"1"
CDS_SEC"1"
PACK_TYPE"0402LF"
WATTAGE"1/16W"
MATERIAL"CHIP"
TOLERANCE"5%"
VALUE"2.2"
BOM_COST"VR_DIMM "
CDS_LIB"pure_quanta"
PART_NUMBER"TMP_QCS-2202JB25";
"A"
$PN"1"43;
"B"
$PN"2"72;
%"Q_CAP"
"1","(-2000,-5650)","0","pure_quanta","I27";
;
LOCATION"PC6556_1"
$SEC"1"
CDS_SEC"1"
VOLTAGE"16V"
MATERIAL"X6S"
TOLERANCE"20%"
PACK_TYPE"C0805"
VALUE"22UF"
CDS_LIB"pure_quanta"
BOM_COST"VR_DIMM "
REUSE_ID"41"
PART_NUMBER"CH6223MEA01";
"B"
$PN"2"10;
"A"
$PN"1"38;
%"ISL99390FRZTR5935"
"1","(-3975,-9350)","0","pure_quanta","I270";
;
LOCATION"PU6504"
SEC"1"
VALUE"ISL99390FRZ-TR5935"
MATERIAL"IC"
PART_TYPE"SMLF"
CDS_LMAN_SYM_OUTLINE"-300,700,250,-650"
CDS_LIB"pure_quanta"
SEC_TYPE""
BOM_COST"VR_DIMM "
NEEDS_NO_SIZE"TRUE"
PART_NUMBER"AL099390004";
"PGND2"
$PN"7_9-20_24"42;
"GL2"
$PN"41"60;
"GL1"
$PN"6"61;
"DNC"
$PN"31"57;
"EN"
$PN"35"72;
"PGND3"
$PN"40"42;
"VOS"
$PN"1"66;
"VIN2"
$PN"30"39;
"PGND1"
$PN"5"42;
"SW"
$PN"10_19"59;
"LSET"
$PN"37"68;
"IOUT"
$PN"38"58;
"TOUT_FLT"
$PN"36"56;
"PVCC"
$PN"4"43;
"PHASE"
$PN"32"70;
"VIN1"
$PN"25_29"39;
"BOOT"
$PN"33"51;
"AGND"
$PN"2"42;
"VCC"
$PN"3"72;
"REFIN"
$PN"39"69;
"PWM"
$PN"34"67;
%"Q_CAP"
"1","(-5775,-8925)","0","pure_quanta","I271";
;
LOCATION"PC6575"
$SEC"1"
CDS_SEC"1"
VALUE"2.2UF"
VOLTAGE"10V"
MATERIAL"X6S"
PACK_TYPE"C0402"
CDS_LIB"pure_quanta"
BOM_COST"VR_DIMM "
TOLERANCE"10%"
PART_NUMBER"CH5222KEB01";
"B"
$PN"2"26;
"A"
$PN"1"72;
%"UNIVERSAL_GND"
"1","(-5775,-9125)","0","pure_quanta_power","I272";
;
CDS_LIB"pure_quanta_power"
HDL_POWER"GND";
"A"26;
%"Q_RES"
"2","(-5725,-9900)","0","pure_quanta","I276";
;
LOCATION"PR6561"
$SEC"1"
CDS_SEC"1"
TOLERANCE"1%"
PACK_TYPE"0402LF"
VALUE"8.87K"
WATTAGE"1/16W"
MATERIAL"EMPTY"
CDS_LIB"pure_quanta"
PART_NUMBER"CS28872FB01";
"A"
$PN"1"68;
"B"
$PN"2"27;
%"UNIVERSAL_GND"
"1","(-5725,-10150)","0","pure_quanta_power","I277";
;
CDS_LIB"pure_quanta_power"
HDL_POWER"GND";
"A"27;
%"Q_CAP"
"1","(-6525,-9775)","0","pure_quanta","I281";
;
LOCATION"PC6576"
$SEC"1"
CDS_SEC"1"
MATERIAL"X7R"
VOLTAGE"50V"
TOLERANCE"10%"
PACK_TYPE"C0402"
VALUE"100NF"
CDS_LIB"pure_quanta"
BOM_COST"VR_CPU"
PART_NUMBER"CH4106K1B01";
"B"
$PN"2"28;
"A"
$PN"1"69;
%"UNIVERSAL_GND"
"1","(-6525,-9975)","0","pure_quanta_power","I282";
;
CDS_LIB"pure_quanta_power"
HDL_POWER"GND";
"A"28;
%"Q_RES"
"2","(-2400,-7175)","0","pure_quanta","I283";
;
LOCATION"PR6555"
$SEC"1"
CDS_SEC"1"
PACK_TYPE"0402LF"
WATTAGE"1/8W"
MATERIAL"EMPTY"
VALUE"1.5"
TOLERANCE"1%"
CDS_LIB"pure_quanta"
PART_NUMBER"CS-1504FB00";
"A"
$PN"1"63;
"B"
$PN"2"29;
%"UNIVERSAL_GND"
"1","(-2400,-7400)","0","pure_quanta_power","I284";
;
CDS_LIB"pure_quanta_power"
HDL_POWER"GND";
"A"29;
%"Q_CAP"
"1","(-2400,-6650)","0","pure_quanta","I285";
;
LOCATION"PC6564"
$SEC"1"
CDS_SEC"1"
MATERIAL"EMPTY"
PACK_TYPE"C0402"
VOLTAGE"50V"
TOLERANCE"10%"
VALUE"560PF"
CDS_LIB"pure_quanta"
PART_NUMBER"CH1566K1B09";
"B"
$PN"2"63;
"A"
$PN"1"45;
%"Q_RES"
"2","(-2400,-10075)","0","pure_quanta","I286";
;
LOCATION"PR6563"
$SEC"1"
CDS_SEC"1"
TOLERANCE"1%"
VALUE"1.5"
MATERIAL"EMPTY"
PACK_TYPE"0402LF"
WATTAGE"1/8W"
CDS_LIB"pure_quanta"
PART_NUMBER"CS-1504FB00";
"A"
$PN"1"62;
"B"
$PN"2"30;
%"UNIVERSAL_GND"
"1","(-2400,-10300)","0","pure_quanta_power","I287";
;
CDS_LIB"pure_quanta_power"
HDL_POWER"GND";
"A"30;
%"Q_CAP"
"1","(-2400,-9550)","0","pure_quanta","I288";
;
LOCATION"PC6585"
$SEC"1"
CDS_SEC"1"
VOLTAGE"50V"
TOLERANCE"10%"
MATERIAL"EMPTY"
PACK_TYPE"C0402"
VALUE"560PF"
CDS_LIB"pure_quanta"
PART_NUMBER"CH1566K1B09";
"B"
$PN"2"62;
"A"
$PN"1"59;
%"UNIVERSAL_POWER"
"1","(-5400,-5125)","0","pure_quanta_power","I289";
;
HDL_POWER"P0V9_RETIMER_CPU0_PVCC"
CDS_LIB"pure_quanta_power";
"A"44;
%"Q_CAP"
"1","(-2500,-5650)","0","pure_quanta","I29";
;
LOCATION"PC6554_1"
$SEC"1"
CDS_SEC"1"
VALUE"1UF"
MATERIAL"X6S"
TOLERANCE"10%"
PACK_TYPE"C0402"
VOLTAGE"25V"
CDS_LIB"pure_quanta"
BOM_COST"VR_DIMM "
PART_NUMBER"CH5104KEB02";
"B"
$PN"2"12;
"A"
$PN"1"38;
%"UNIVERSAL_GND"
"1","(2000,-6000)","0","pure_quanta_power","I290";
;
CDS_LIB"pure_quanta_power"
HDL_POWER"GND";
"A"31;
%"Q_CAP"
"1","(2000,-5675)","0","pure_quanta","I291";
;
LOCATION"PC6562"
$SEC"1"
CDS_SEC"1"
MATERIAL"X7R"
PACK_TYPE"0402"
VOLTAGE"25V"
VALUE"0.1UF"
TOLERANCE"10%"
CDS_LIB"pure_quanta"
PART_NUMBER"CH4104K1B00";
"B"
$PN"2"31;
"A"
$PN"1"32;
%"Q_CAP"
"2","(-1125,-6100)","0","pure_quanta","I30";
;
LOCATION"PC6563"
$SEC"1"
CDS_SEC"1"
VOLTAGE"50V"
PACK_TYPE"C0402"
TOLERANCE"10%"
MATERIAL"X7R"
VALUE"100NF"
CDS_LIB"pure_quanta"
REUSE_ID"55"
BOM_COST"VR_DIMM "
PART_NUMBER"CH4106K1B01";
"A"
$PN"1"50;
"B"
$PN"2"48;
%"Q_CAP"
"1","(-1150,-6600)","0","pure_quanta","I33";
;
LOCATION"PC6565"
$SEC"1"
CDS_SEC"1"
MATERIAL"X7R"
VOLTAGE"50V"
VALUE"100NF"
TOLERANCE"10%"
PACK_TYPE"C0402"
CDS_LIB"pure_quanta"
BOM_COST"VR_DIMM "
PART_NUMBER"CH4106K1B01";
"B"
$PN"2"37;
"A"
$PN"1"35;
%"Q_INDUCTOR"
"1","(-1925,-6425)","0","pure_quanta","I34";
;
LOCATION"PL6505"
SEC"1"
PACK_TYPE"SMLF"
VALUE"120NH/69A"
MATERIAL"IND"
CDS_LIB"pure_quanta"
SEC_TYPE"SMLF"
BOM_COST"VR_DIMM "
NEEDS_NO_SIZE"TRUE"
PART_NUMBER"CV+12^0EZ03";
"1"
$PN"1"45;
"2"
$PN"2"35;
%"UNIVERSAL_POWER"
"1","(2000,-5200)","0","pure_quanta_power","I4";
;
HDL_POWER"P12V_AUX"
BOM_COST"VR_DIMM "
CDS_LIB"pure_quanta_power";
"A"32;
%"Q_RES"
"1","(-2150,-7625)","0","pure_quanta","I42";
;
LOCATION"PR6556"
$SEC"1"
CDS_SEC"1"
MATERIAL"CHIP"
WATTAGE"1/16W"
TOLERANCE"5%"
VALUE"0"
PACK_TYPE"0402LF"
CDS_LIB"pure_quanta"
BOM_COST"VR_DIMM "
PART_NUMBER"CS00002JB13";
"B"
$PN"2"35;
"A"
$PN"1"49;
%"Q_CAP"
"1","(-5200,-5500)","0","pure_quanta","I47";
;
LOCATION"PC6550_09P0_1"
$SEC"1"
CDS_SEC"1"
MATERIAL"X6S"
VOLTAGE"10V"
PACK_TYPE"C0402"
TOLERANCE"10%"
VALUE"2.2UF"
CDS_LIB"pure_quanta"
BOM_COST"VR_DIMM "
PART_NUMBER"CH5222KEB01";
"B"
$PN"2"6;
"A"
$PN"1"44;
%"Q_CAP"
"1","(-5900,-6025)","0","pure_quanta","I48";
;
LOCATION"PC6552"
$SEC"1"
CDS_SEC"1"
PACK_TYPE"C0402"
VOLTAGE"10V"
MATERIAL"X6S"
VALUE"2.2UF"
CDS_LIB"pure_quanta"
BOM_COST"VR_DIMM "
TOLERANCE"10%"
PART_NUMBER"CH5222KEB01";
"B"
$PN"2"5;
"A"
$PN"1"46;
%"ISL99390FRZTR5935"
"1","(-4100,-6450)","0","pure_quanta","I53";
;
LOCATION"PU6503"
SEC"1"
MATERIAL"IC"
PART_TYPE"SMLF"
VALUE"ISL99390FRZ-TR5935"
CDS_LMAN_SYM_OUTLINE"-300,700,250,-650"
CDS_LIB"pure_quanta"
SEC_TYPE""
BOM_COST"VR_DIMM "
NEEDS_NO_SIZE"TRUE"
PART_NUMBER"AL099390004";
"PGND2"
$PN"7_9-20_24"36;
"GL2"
$PN"41"71;
"GL1"
$PN"6"53;
"DNC"
$PN"31"64;
"EN"
$PN"35"46;
"PGND3"
$PN"40"36;
"VOS"
$PN"1"49;
"VIN2"
$PN"30"38;
"PGND1"
$PN"5"36;
"SW"
$PN"10_19"45;
"LSET"
$PN"37"65;
"IOUT"
$PN"38"33;
"TOUT_FLT"
$PN"36"54;
"PVCC"
$PN"4"44;
"PHASE"
$PN"32"48;
"VIN1"
$PN"25_29"38;
"BOOT"
$PN"33"47;
"AGND"
$PN"2"36;
"VCC"
$PN"3"46;
"REFIN"
$PN"39"34;
"PWM"
$PN"34"55;
%"Q_RES"
"2","(-5900,-5500)","0","pure_quanta","I58";
;
LOCATION"PR6552"
$SEC"1"
CDS_SEC"1"
PACK_TYPE"0402LF"
VALUE"2.2"
TOLERANCE"5%"
MATERIAL"CHIP"
WATTAGE"1/16W"
CDS_LIB"pure_quanta"
BOM_COST"VR_DIMM "
PART_NUMBER"TMP_QCS-2202JB25";
"A"
$PN"1"44;
"B"
$PN"2"46;
%"Q_CAP"
"1","(-3000,-5650)","0","pure_quanta","I6";
;
LOCATION"PC6555_1"
$SEC"1"
CDS_SEC"1"
MATERIAL"X7R"
VOLTAGE"50V"
VALUE"3300PF"
TOLERANCE"10%"
PACK_TYPE"0402"
CDS_LIB"pure_quanta"
BOM_COST"VR_DIMM "
PART_NUMBER"TMP_QCH2336K1B12";
"B"
$PN"2"11;
"A"
$PN"1"38;
%"Q_CAP"
"1","(-6650,-6875)","0","pure_quanta","I68";
;
LOCATION"PC6553_1"
$SEC"1"
CDS_SEC"1"
PACK_TYPE"C0402"
MATERIAL"X7R"
TOLERANCE"10%"
VALUE"100NF"
VOLTAGE"50V"
CDS_LIB"pure_quanta"
BOM_COST"VR_CPU"
PART_NUMBER"CH4106K1B01";
"B"
$PN"2"3;
"A"
$PN"1"34;
END.
